(kicad_pcb
	(version 20260206)
	(generator "pcbnew")
	(generator_version "10.0")
	(general
		(thickness 1.6)
		(legacy_teardrops no)
	)
	(paper "A4")
	(title_block
		(title "Bryce Canyon_IOM_M2_16342-2_OCP.brd")
		(comment 1 "Bryce Canyon / footprints 421-428 of 1146")
	)
	(layers
		(0 "F.Cu" signal "TOP")
		(4 "In1.Cu" signal "L2GND")
		(6 "In2.Cu" signal "L3")
		(8 "In3.Cu" signal "L4VCC")
		(10 "In4.Cu" signal "L5VCC")
		(12 "In5.Cu" signal "L6")
		(14 "In6.Cu" signal "L7GND")
		(2 "B.Cu" signal "BOTTOM")
		(9 "F.Adhes" user "F.Adhesive")
		(11 "B.Adhes" user "B.Adhesive")
		(13 "F.Paste" user "Package Geometry/Pastemask Top")
		(15 "B.Paste" user "Package Geometry/Pastemask Bottom")
		(5 "F.SilkS" user "Ref Des/Silkscreen Top")
		(7 "B.SilkS" user "Ref Des/Silkscreen Bottom")
		(1 "F.Mask" user "Board Geometry/Soldermask Top")
		(3 "B.Mask" user "Board Geometry/Soldermask Bottom")
		(17 "Dwgs.User" user "User.Drawings")
		(19 "Cmts.User" user "User.Comments")
		(21 "Eco1.User" user "User.Eco1")
		(23 "Eco2.User" user "User.Eco2")
		(25 "Edge.Cuts" user "Board Geometry/Outline")
		(27 "Margin" user)
		(31 "F.CrtYd" user "Package Geometry/Place Bound Top")
		(29 "B.CrtYd" user "Package Geometry/Place Bound Bottom")
		(35 "F.Fab" user "Ref Des/Assembly Top")
		(33 "B.Fab" user "Ref Des/Assembly Bottom")
	)
	(footprint ""
		(layer "F.Cu")
		(at 99.3648 -150.6728 -90)
		(property "Reference" "R36"
			(at 0 0 270)
			(layer "F.SilkS")
			(hide yes)
			(effects
				(font
					(size 1.27 1.27)
				)
			)
		)
		(property "Value" "4K7R2F-GP"
			(at 0.064008 -3.993896 270)
			(unlocked yes)
			(layer "F.Fab")
			(hide yes)
			(effects
				(font
					(size 1.016 1.016)
					(thickness 0.1524)
				)
			)
		)
		(property "Device Type" "R402H16"
			(at 0.064008 -5.517896 270)
			(unlocked yes)
			(layer "F.Fab")
			(hide yes)
			(effects
				(font
					(size 1.016 1.016)
					(thickness 0.1524)
				)
			)
		)
		(duplicate_pad_numbers_are_jumpers no)
		(fp_line
			(start -0.508 -0.9398)
			(end -0.508 0.9398)
			(stroke
				(width 0.1524)
				(type default)
			)
			(layer "F.SilkS")
		)
		(fp_line
			(start 0.508 -0.9398)
			(end -0.508 -0.9398)
			(stroke
				(width 0.1524)
				(type default)
			)
			(layer "F.SilkS")
		)
		(fp_rect
			(start -0.508 0.9398)
			(end 0.508 -0.9398)
			(stroke
				(width 0)
				(type default)
			)
			(fill no)
			(layer "F.CrtYd")
		)
		(fp_rect
			(start -0.508 0.9398)
			(end 0.508 -0.9398)
			(stroke
				(width 0)
				(type default)
			)
			(fill no)
			(layer "F.Fab")
		)
		(pad "1" smd custom
			(at 0 -0.4445 270)
			(size 0.1397 0.1397)
			(layers "F.Cu" "F.Mask" "F.Paste")
			(net "P3V3_STBY")
			(options
				(clearance outline)
				(anchor circle)
			)
			(primitives
				(gr_poly
					(pts
						(arc
							(start -0.1778 -0.2794)
							(mid -0.249642 -0.249642)
							(end -0.2794 -0.1778)
						)
						(arc
							(start -0.2794 0.1778)
							(mid -0.249642 0.249642)
							(end -0.1778 0.2794)
						)
						(arc
							(start 0.1778 0.2794)
							(mid 0.249642 0.249642)
							(end 0.2794 0.1778)
						)
						(arc
							(start 0.2794 -0.1778)
							(mid 0.249642 -0.249642)
							(end 0.1778 -0.2794)
						)
					)
					(width 0)
					(fill yes)
				)
			)
		)
		(pad "2" smd custom
			(at 0 0.4445 270)
			(size 0.1397 0.1397)
			(layers "F.Cu" "F.Mask" "F.Paste")
			(net "USB_EN_4")
			(options
				(clearance outline)
				(anchor circle)
			)
			(primitives
				(gr_poly
					(pts
						(arc
							(start -0.1778 -0.2794)
							(mid -0.249642 -0.249642)
							(end -0.2794 -0.1778)
						)
						(arc
							(start -0.2794 0.1778)
							(mid -0.249642 0.249642)
							(end -0.1778 0.2794)
						)
						(arc
							(start 0.1778 0.2794)
							(mid 0.249642 0.249642)
							(end 0.2794 0.1778)
						)
						(arc
							(start 0.2794 -0.1778)
							(mid 0.249642 -0.249642)
							(end 0.1778 -0.2794)
						)
					)
					(width 0)
					(fill yes)
				)
			)
		)
	)
	(footprint ""
		(layer "F.Cu")
		(at 70.2056 -163.721288 -90)
		(property "Reference" "R73"
			(at 0 0 270)
			(layer "F.SilkS")
			(hide yes)
			(effects
				(font
					(size 1.27 1.27)
				)
			)
		)
		(property "Value" "4K75R2F-1-GP"
			(at 0.064008 -3.993896 270)
			(unlocked yes)
			(layer "F.Fab")
			(hide yes)
			(effects
				(font
					(size 1.016 1.016)
					(thickness 0.1524)
				)
			)
		)
		(property "Device Type" "R402H16"
			(at 0.064008 -5.517896 270)
			(unlocked yes)
			(layer "F.Fab")
			(hide yes)
			(effects
				(font
					(size 1.016 1.016)
					(thickness 0.1524)
				)
			)
		)
		(duplicate_pad_numbers_are_jumpers no)
		(fp_line
			(start -0.508 -0.9398)
			(end -0.508 0.9398)
			(stroke
				(width 0.1524)
				(type default)
			)
			(layer "F.SilkS")
		)
		(fp_line
			(start 0.508 -0.9398)
			(end -0.508 -0.9398)
			(stroke
				(width 0.1524)
				(type default)
			)
			(layer "F.SilkS")
		)
		(fp_rect
			(start -0.508 0.9398)
			(end 0.508 -0.9398)
			(stroke
				(width 0)
				(type default)
			)
			(fill no)
			(layer "F.CrtYd")
		)
		(fp_rect
			(start -0.508 0.9398)
			(end 0.508 -0.9398)
			(stroke
				(width 0)
				(type default)
			)
			(fill no)
			(layer "F.Fab")
		)
		(pad "1" smd custom
			(at 0 -0.4445 270)
			(size 0.1397 0.1397)
			(layers "F.Cu" "F.Mask" "F.Paste")
			(net "P3V3_STBY")
			(options
				(clearance outline)
				(anchor circle)
			)
			(primitives
				(gr_poly
					(pts
						(arc
							(start -0.1778 -0.2794)
							(mid -0.249642 -0.249642)
							(end -0.2794 -0.1778)
						)
						(arc
							(start -0.2794 0.1778)
							(mid -0.249642 0.249642)
							(end -0.1778 0.2794)
						)
						(arc
							(start 0.1778 0.2794)
							(mid 0.249642 0.249642)
							(end 0.2794 0.1778)
						)
						(arc
							(start 0.2794 -0.1778)
							(mid 0.249642 -0.249642)
							(end 0.1778 -0.2794)
						)
					)
					(width 0)
					(fill yes)
				)
			)
		)
		(pad "2" smd custom
			(at 0 0.4445 270)
			(size 0.1397 0.1397)
			(layers "F.Cu" "F.Mask" "F.Paste")
			(net "BMC_TPM_RST_N")
			(options
				(clearance outline)
				(anchor circle)
			)
			(primitives
				(gr_poly
					(pts
						(arc
							(start -0.1778 -0.2794)
							(mid -0.249642 -0.249642)
							(end -0.2794 -0.1778)
						)
						(arc
							(start -0.2794 0.1778)
							(mid -0.249642 0.249642)
							(end -0.1778 0.2794)
						)
						(arc
							(start 0.1778 0.2794)
							(mid 0.249642 0.249642)
							(end 0.2794 0.1778)
						)
						(arc
							(start 0.2794 -0.1778)
							(mid 0.249642 -0.249642)
							(end 0.1778 -0.2794)
						)
					)
					(width 0)
					(fill yes)
				)
			)
		)
	)
	(footprint ""
		(layer "F.Cu")
		(at 56.7436 -162.4838)
		(property "Reference" "R402"
			(at 0 0 0)
			(layer "F.SilkS")
			(hide yes)
			(effects
				(font
					(size 1.27 1.27)
				)
			)
		)
		(property "Value" "330R2F-GP"
			(at 0.064008 -3.993896 0)
			(unlocked yes)
			(layer "F.Fab")
			(hide yes)
			(effects
				(font
					(size 1.016 1.016)
					(thickness 0.1524)
				)
			)
		)
		(property "Device Type" "R402H16"
			(at 0.064008 -5.517896 0)
			(unlocked yes)
			(layer "F.Fab")
			(hide yes)
			(effects
				(font
					(size 1.016 1.016)
					(thickness 0.1524)
				)
			)
		)
		(duplicate_pad_numbers_are_jumpers no)
		(fp_line
			(start -0.508 -0.9398)
			(end -0.508 0.9398)
			(stroke
				(width 0.1524)
				(type default)
			)
			(layer "F.SilkS")
		)
		(fp_line
			(start 0.508 -0.9398)
			(end -0.508 -0.9398)
			(stroke
				(width 0.1524)
				(type default)
			)
			(layer "F.SilkS")
		)
		(fp_rect
			(start -0.508 0.9398)
			(end 0.508 -0.9398)
			(stroke
				(width 0)
				(type default)
			)
			(fill no)
			(layer "F.CrtYd")
		)
		(fp_rect
			(start -0.508 0.9398)
			(end 0.508 -0.9398)
			(stroke
				(width 0)
				(type default)
			)
			(fill no)
			(layer "F.Fab")
		)
		(pad "1" smd custom
			(at 0 -0.4445)
			(size 0.1397 0.1397)
			(layers "F.Cu" "F.Mask" "F.Paste")
			(net "P1V8_STBY")
			(options
				(clearance outline)
				(anchor circle)
			)
			(primitives
				(gr_poly
					(pts
						(arc
							(start -0.1778 -0.2794)
							(mid -0.249642 -0.249642)
							(end -0.2794 -0.1778)
						)
						(arc
							(start -0.2794 0.1778)
							(mid -0.249642 0.249642)
							(end -0.1778 0.2794)
						)
						(arc
							(start 0.1778 0.2794)
							(mid 0.249642 0.249642)
							(end 0.2794 0.1778)
						)
						(arc
							(start 0.2794 -0.1778)
							(mid 0.249642 -0.249642)
							(end 0.1778 -0.2794)
						)
					)
					(width 0)
					(fill yes)
				)
			)
		)
		(pad "2" smd custom
			(at 0 0.4445)
			(size 0.1397 0.1397)
			(layers "F.Cu" "F.Mask" "F.Paste")
			(net "ADC_P1V8_STBY")
			(options
				(clearance outline)
				(anchor circle)
			)
			(primitives
				(gr_poly
					(pts
						(arc
							(start -0.1778 -0.2794)
							(mid -0.249642 -0.249642)
							(end -0.2794 -0.1778)
						)
						(arc
							(start -0.2794 0.1778)
							(mid -0.249642 0.249642)
							(end -0.1778 0.2794)
						)
						(arc
							(start 0.1778 0.2794)
							(mid 0.249642 0.249642)
							(end 0.2794 0.1778)
						)
						(arc
							(start 0.2794 -0.1778)
							(mid 0.249642 -0.249642)
							(end 0.1778 -0.2794)
						)
					)
					(width 0)
					(fill yes)
				)
			)
		)
	)
	(footprint ""
		(layer "F.Cu")
		(at 185.399426 -140.000482 -135)
		(property "Reference" "VIA58"
			(at 0 0 225)
			(layer "F.SilkS")
			(hide yes)
			(effects
				(font
					(size 1.27 1.27)
				)
			)
		)
		(property "Value" "85OHM-8L-1D6MM-L16L18-GP"
			(at 4.064105 0.609655 225)
			(unlocked yes)
			(layer "F.Fab")
			(hide yes)
			(effects
				(font
					(size 1.016 1.016)
					(thickness 0.1524)
				)
			)
		)
		(property "Device Type" "VIA-PCIE-4P-368076"
			(at 4.064105 -0.914474 225)
			(unlocked yes)
			(layer "F.Fab")
			(hide yes)
			(effects
				(font
					(size 1.016 1.016)
					(thickness 0.1524)
				)
			)
		)
		(duplicate_pad_numbers_are_jumpers no)
		(fp_poly
			(pts
				(xy -1.841491 -0.381057) (xy 1.841509 -0.381058) (xy 1.841508 0.380942) (xy -1.841491 0.380942)
			)
			(stroke
				(width 0)
				(type default)
			)
			(fill no)
			(layer "F.CrtYd")
		)
		(fp_poly
			(pts
				(xy -1.841491 -0.381057) (xy 1.841509 -0.381058) (xy 1.841508 0.380942) (xy -1.841491 0.380942)
			)
			(stroke
				(width 0)
				(type default)
			)
			(fill no)
			(layer "F.Fab")
		)
		(pad "1" thru_hole circle
			(at -1.460499 0 225)
			(size 0.508 0.508)
			(drill 0.254)
			(layers "*.Cu" "*.Mask")
			(remove_unused_layers no)
			(net "GND")
			(clearance 0.127)
			(thermal_gap 0.127)
		)
		(pad "2" thru_hole circle
			(at -0.4445 0 225)
			(size 0.508 0.508)
			(drill 0.254)
			(layers "*.Cu" "*.Mask")
			(remove_unused_layers no)
			(net "PCIE_COMP_TO_IOM_12_DP")
			(clearance 0.127)
			(thermal_gap 0.127)
		)
		(pad "3" thru_hole circle
			(at 0.4445 0 225)
			(size 0.508 0.508)
			(drill 0.254)
			(layers "*.Cu" "*.Mask")
			(remove_unused_layers no)
			(net "PCIE_COMP_TO_IOM_12_DN")
			(clearance 0.127)
			(thermal_gap 0.127)
		)
		(pad "4" thru_hole circle
			(at 1.460499 0 225)
			(size 0.508 0.508)
			(drill 0.254)
			(layers "*.Cu" "*.Mask")
			(remove_unused_layers no)
			(net "GND")
			(clearance 0.127)
			(thermal_gap 0.127)
		)
	)
	(footprint ""
		(layer "F.Cu")
		(at 84.963 -150.876 -90)
		(property "Reference" "U12"
			(at 0 0 270)
			(layer "F.SilkS")
			(hide yes)
			(effects
				(font
					(size 1.27 1.27)
				)
			)
		)
		(property "Value" "NX3L1G66GW-GP"
			(at -2.3368 -8.6868 270)
			(unlocked yes)
			(layer "F.Fab")
			(hide yes)
			(effects
				(font
					(size 1.016 1.016)
					(thickness 0.1524)
				)
			)
		)
		(property "Device Type" "SC70-5H44"
			(at -2.3114 -10.414 270)
			(unlocked yes)
			(layer "F.Fab")
			(hide yes)
			(effects
				(font
					(size 1.016 1.016)
					(thickness 0.1524)
				)
			)
		)
		(duplicate_pad_numbers_are_jumpers no)
		(fp_line
			(start -1.27 1.7018)
			(end -1.27 -1.7018)
			(stroke
				(width 0.1524)
				(type default)
			)
			(layer "F.SilkS")
		)
		(fp_line
			(start 1.27 1.7018)
			(end -1.27 1.7018)
			(stroke
				(width 0.1524)
				(type default)
			)
			(layer "F.SilkS")
		)
		(fp_line
			(start -1.27 -1.7018)
			(end 1.27 -1.7018)
			(stroke
				(width 0.1524)
				(type default)
			)
			(layer "F.SilkS")
		)
		(fp_line
			(start 1.27 -1.7018)
			(end 1.27 1.7018)
			(stroke
				(width 0.1524)
				(type default)
			)
			(layer "F.SilkS")
		)
		(fp_line
			(start 0.6604 -1.8034)
			(end 1.3843 -1.8034)
			(stroke
				(width 0.3302)
				(type default)
			)
			(layer "F.SilkS")
		)
		(fp_line
			(start 1.3843 -1.8034)
			(end 1.3843 -1.1176)
			(stroke
				(width 0.3302)
				(type default)
			)
			(layer "F.SilkS")
		)
		(fp_rect
			(start -1.524 1.9558)
			(end 1.524 -1.9558)
			(stroke
				(width 0)
				(type default)
			)
			(fill no)
			(layer "F.CrtYd")
		)
		(fp_poly
			(pts
				(xy -1.524 -1.9558) (xy 1.524 -1.9558) (xy 1.524 1.9558) (xy -1.524 1.9558)
			)
			(stroke
				(width 0)
				(type default)
			)
			(fill no)
			(layer "F.Fab")
		)
		(pad "1" smd rect
			(at 0.65024 -0.8255 270)
			(size 0.4064 1.2192)
			(layers "F.Cu" "F.Mask" "F.Paste")
			(net "I2C_BMC_COMP_SCL_R")
		)
		(pad "2" smd rect
			(at 0 -0.8255 270)
			(size 0.4064 1.2192)
			(layers "F.Cu" "F.Mask" "F.Paste")
			(net "I2C_BMC_COMP_SCL_OUT")
		)
		(pad "3" smd rect
			(at -0.65024 -0.8255 270)
			(size 0.4064 1.2192)
			(layers "F.Cu" "F.Mask" "F.Paste")
			(net "GND")
		)
		(pad "4" smd rect
			(at -0.65024 0.8255 270)
			(size 0.4064 1.2192)
			(layers "F.Cu" "F.Mask" "F.Paste")
			(net "COMP_PWR_EN")
		)
		(pad "5" smd rect
			(at 0.65024 0.8255 270)
			(size 0.4064 1.2192)
			(layers "F.Cu" "F.Mask" "F.Paste")
			(net "P3V3_STBY")
		)
	)
	(footprint ""
		(layer "F.Cu")
		(at 89.0016 -134.6708)
		(property "Reference" "R137"
			(at 0 0 0)
			(layer "F.SilkS")
			(hide yes)
			(effects
				(font
					(size 1.27 1.27)
				)
			)
		)
		(property "Value" "8K2R2J-3-GP"
			(at 0.064008 -3.993896 0)
			(unlocked yes)
			(layer "F.Fab")
			(hide yes)
			(effects
				(font
					(size 1.016 1.016)
					(thickness 0.1524)
				)
			)
		)
		(property "Device Type" "R402H16"
			(at 0.064008 -5.517896 0)
			(unlocked yes)
			(layer "F.Fab")
			(hide yes)
			(effects
				(font
					(size 1.016 1.016)
					(thickness 0.1524)
				)
			)
		)
		(duplicate_pad_numbers_are_jumpers no)
		(fp_line
			(start -0.508 -0.9398)
			(end -0.508 0.9398)
			(stroke
				(width 0.1524)
				(type default)
			)
			(layer "F.SilkS")
		)
		(fp_line
			(start 0.508 -0.9398)
			(end -0.508 -0.9398)
			(stroke
				(width 0.1524)
				(type default)
			)
			(layer "F.SilkS")
		)
		(fp_rect
			(start -0.508 0.9398)
			(end 0.508 -0.9398)
			(stroke
				(width 0)
				(type default)
			)
			(fill no)
			(layer "F.CrtYd")
		)
		(fp_rect
			(start -0.508 0.9398)
			(end 0.508 -0.9398)
			(stroke
				(width 0)
				(type default)
			)
			(fill no)
			(layer "F.Fab")
		)
		(pad "1" smd custom
			(at 0 -0.4445)
			(size 0.1397 0.1397)
			(layers "F.Cu" "F.Mask" "F.Paste")
			(net "EEPROM_A1")
			(options
				(clearance outline)
				(anchor circle)
			)
			(primitives
				(gr_poly
					(pts
						(arc
							(start -0.1778 -0.2794)
							(mid -0.249642 -0.249642)
							(end -0.2794 -0.1778)
						)
						(arc
							(start -0.2794 0.1778)
							(mid -0.249642 0.249642)
							(end -0.1778 0.2794)
						)
						(arc
							(start 0.1778 0.2794)
							(mid 0.249642 0.249642)
							(end 0.2794 0.1778)
						)
						(arc
							(start 0.2794 -0.1778)
							(mid 0.249642 -0.249642)
							(end 0.1778 -0.2794)
						)
					)
					(width 0)
					(fill yes)
				)
			)
		)
		(pad "2" smd custom
			(at 0 0.4445)
			(size 0.1397 0.1397)
			(layers "F.Cu" "F.Mask" "F.Paste")
			(net "GND")
			(options
				(clearance outline)
				(anchor circle)
			)
			(primitives
				(gr_poly
					(pts
						(arc
							(start -0.1778 -0.2794)
							(mid -0.249642 -0.249642)
							(end -0.2794 -0.1778)
						)
						(arc
							(start -0.2794 0.1778)
							(mid -0.249642 0.249642)
							(end -0.1778 0.2794)
						)
						(arc
							(start 0.1778 0.2794)
							(mid 0.249642 0.249642)
							(end 0.2794 0.1778)
						)
						(arc
							(start 0.2794 -0.1778)
							(mid 0.249642 -0.249642)
							(end 0.1778 -0.2794)
						)
					)
					(width 0)
					(fill yes)
				)
			)
		)
	)
	(footprint ""
		(layer "F.Cu")
		(at 14.351 -13.208 -90)
		(property "Reference" "C529"
			(at 0 0 270)
			(layer "F.SilkS")
			(hide yes)
			(effects
				(font
					(size 1.27 1.27)
				)
			)
		)
		(property "Value" "SC1000P2KV6KX-GP-U"
			(at 0.0508 -3.5052 270)
			(unlocked yes)
			(layer "F.Fab")
			(hide yes)
			(effects
				(font
					(size 1.016 1.016)
					(thickness 0.1524)
				)
			)
		)
		(property "Device Type" "C1206H58"
			(at 0.0508 -5.0292 270)
			(unlocked yes)
			(layer "F.Fab")
			(hide yes)
			(effects
				(font
					(size 1.016 1.016)
					(thickness 0.1524)
				)
			)
		)
		(duplicate_pad_numbers_are_jumpers no)
		(fp_line
			(start -1.016 2.2352)
			(end -1.016 0.8128)
			(stroke
				(width 0.1524)
				(type default)
			)
			(layer "F.SilkS")
		)
		(fp_line
			(start 1.016 2.2352)
			(end -1.016 2.2352)
			(stroke
				(width 0.1524)
				(type default)
			)
			(layer "F.SilkS")
		)
		(fp_line
			(start 1.016 0.8382)
			(end 1.016 2.2352)
			(stroke
				(width 0.1524)
				(type default)
			)
			(layer "F.SilkS")
		)
		(fp_line
			(start -1.016 -2.2352)
			(end -1.016 -0.8382)
			(stroke
				(width 0.1524)
				(type default)
			)
			(layer "F.SilkS")
		)
		(fp_line
			(start 1.016 -2.2352)
			(end 1.016 -0.8382)
			(stroke
				(width 0.1524)
				(type default)
			)
			(layer "F.SilkS")
		)
		(fp_line
			(start 1.016 -2.2352)
			(end -1.016 -2.2352)
			(stroke
				(width 0.1524)
				(type default)
			)
			(layer "F.SilkS")
		)
		(fp_rect
			(start -1.0922 2.3114)
			(end 1.0922 -2.3114)
			(stroke
				(width 0)
				(type default)
			)
			(fill no)
			(layer "F.CrtYd")
		)
		(fp_poly
			(pts
				(xy -1.0922 -2.3114) (xy 1.0922 -2.3114) (xy 1.0922 2.3114) (xy -1.0922 2.3114)
			)
			(stroke
				(width 0)
				(type default)
			)
			(fill no)
			(layer "F.Fab")
		)
		(pad "1" smd rect
			(at 0 -1.397 270)
			(size 1.651 1.27)
			(layers "F.Cu" "F.Mask" "F.Paste")
			(net "RST_BTN_GND")
		)
		(pad "2" smd rect
			(at 0 1.397 270)
			(size 1.651 1.27)
			(layers "F.Cu" "F.Mask" "F.Paste")
			(net "GND")
		)
	)
	(footprint ""
		(layer "F.Cu")
		(at 29.755846 -186.56681 180)
		(property "Reference" "C177"
			(at 0 0 180)
			(layer "F.SilkS")
			(hide yes)
			(effects
				(font
					(size 1.27 1.27)
				)
			)
		)
		(property "Value" "SC10U16V5KX-7-GP-U"
			(at -0.0762 -6.1214 180)
			(unlocked yes)
			(layer "F.Fab")
			(hide yes)
			(effects
				(font
					(size 1.016 1.016)
					(thickness 0.1524)
				)
			)
		)
		(property "Device Type" "C805H58"
			(at -0.0762 -8.1534 180)
			(unlocked yes)
			(layer "F.Fab")
			(hide yes)
			(effects
				(font
					(size 1.016 1.016)
					(thickness 0.1524)
				)
			)
		)
		(duplicate_pad_numbers_are_jumpers no)
		(fp_line
			(start 0.635 0)
			(end -0.635 0)
			(stroke
				(width 0.508)
				(type default)
			)
			(layer "F.SilkS")
		)
		(fp_rect
			(start -0.9652 1.778)
			(end 0.9652 -1.778)
			(stroke
				(width 0)
				(type default)
			)
			(fill no)
			(layer "F.CrtYd")
		)
		(fp_poly
			(pts
				(xy -0.9652 -1.778) (xy 0.9652 -1.778) (xy 0.9652 1.778) (xy -0.9652 1.778)
			)
			(stroke
				(width 0)
				(type default)
			)
			(fill no)
			(layer "F.Fab")
		)
		(pad "1" smd rect
			(at 0 -0.9652 180)
			(size 1.397 1.143)
			(layers "F.Cu" "F.Mask" "F.Paste")
			(net "P12V_STBY_VIN_PU2")
		)
		(pad "2" smd rect
			(at 0 0.9652 180)
			(size 1.397 1.143)
			(layers "F.Cu" "F.Mask" "F.Paste")
			(net "GND")
		)
	)
)
